# S9S_MB_2U (Grand Teton) — schematic netlist excerpt (pin names and nets, part order shuffled) for the footprints in the layout excerpt that follows; sources: Cadence DE-HDL packaged netlist, KiCad conversion of 03242023_DA0F0TMBIJ0_F0T_Motherboard_J_brd_V01_OCP.brd

C146  Q_CAP_DIFFBUS  DIFF BUS_0.22UF 6.3V 20% X6S  pkg C0201  page 178 : \1\ = DMI_CPU0_PCH_TX_C_DP<4> ; \2\ = DMI_CPU0_PCH_TX_DP<4>
R4452  Q_RES  10K 1% EMPTY  pkg 0402LF  page 196 : A = P3V3_AUX ; B = RST_USB_HUB_2_R_N

(kicad_pcb
	(version 20260206)
	(generator "pcbnew")
	(generator_version "10.0")
	(general
		(thickness 1.6)
		(legacy_teardrops no)
	)
	(paper "A4")
	(title_block
		(title "03242023_DA0F0TMBIJ0_F0T_Motherboard_J_brd_V01_OCP.brd")
		(comment 1 "Grand Teton / footprints 2367-2368 of 6105")
	)
	(layers
		(0 "F.Cu" signal "TOP")
		(4 "In1.Cu" signal "GND")
		(6 "In2.Cu" signal "IN1")
		(8 "In3.Cu" signal "GND1")
		(10 "In4.Cu" signal "IN2")
		(12 "In5.Cu" signal "GND2")
		(14 "In6.Cu" signal "IN3")
		(16 "In7.Cu" signal "GND3")
		(18 "In8.Cu" signal "VCC")
		(20 "In9.Cu" signal "VCC1")
		(22 "In10.Cu" signal "GND4")
		(24 "In11.Cu" signal "IN4")
		(26 "In12.Cu" signal "GND5")
		(28 "In13.Cu" signal "IN5")
		(30 "In14.Cu" signal "GND6")
		(32 "In15.Cu" signal "IN6")
		(34 "In16.Cu" signal "GND7")
		(2 "B.Cu" signal "BOTTOM")
		(9 "F.Adhes" user "F.Adhesive")
		(11 "B.Adhes" user "B.Adhesive")
		(13 "F.Paste" user "Package Geometry/Pastemask Top")
		(15 "B.Paste" user "Package Geometry/Pastemask Bottom")
		(5 "F.SilkS" user "Ref Des/Silkscreen Top")
		(7 "B.SilkS" user "Ref Des/Silkscreen Bottom")
		(1 "F.Mask" user "Board Geometry/Soldermask Top")
		(3 "B.Mask" user "Board Geometry/Soldermask Bottom")
		(17 "Dwgs.User" user "User.Drawings")
		(19 "Cmts.User" user "User.Comments")
		(21 "Eco1.User" user "User.Eco1")
		(23 "Eco2.User" user "User.Eco2")
		(25 "Edge.Cuts" user "Board Geometry/Outline")
		(27 "Margin" user)
		(31 "F.CrtYd" user "Package Geometry/Place Bound Top")
		(29 "B.CrtYd" user "Package Geometry/Place Bound Bottom")
		(35 "F.Fab" user "Ref Des/Assembly Top")
		(33 "B.Fab" user "Ref Des/Assembly Bottom")
	)
	(footprint ""
		(layer "F.Cu")
		(at 156.053536 -31.341568 90)
		(property "Reference" "R4452"
			(at 0 0 90)
			(layer "F.SilkS")
			(hide yes)
			(effects
				(font
					(size 1.27 1.27)
				)
			)
		)
		(property "Value" ""
			(at 0 0 90)
			(layer "F.Fab")
			(effects
				(font
					(size 1.27 1.27)
				)
			)
		)
		(duplicate_pad_numbers_are_jumpers no)
		(fp_line
			(start 0.7874 -0.4064)
			(end 0.7874 0.4064)
			(stroke
				(width 0.1524)
				(type default)
			)
			(layer "F.SilkS")
		)
		(fp_line
			(start -0.7874 -0.4064)
			(end 0.7874 -0.4064)
			(stroke
				(width 0.1524)
				(type default)
			)
			(layer "F.SilkS")
		)
		(fp_line
			(start 0.7874 0.4064)
			(end -0.7874 0.4064)
			(stroke
				(width 0.1524)
				(type default)
			)
			(layer "F.SilkS")
		)
		(fp_line
			(start -0.7874 0.4064)
			(end -0.7874 -0.4064)
			(stroke
				(width 0.1524)
				(type default)
			)
			(layer "F.SilkS")
		)
		(fp_line
			(start -0.12065 -0.305054)
			(end -0.12065 -0.2794)
			(stroke
				(width 0.1)
				(type default)
			)
			(layer "F.Fab")
		)
		(fp_line
			(start -0.67945 -0.305054)
			(end -0.12065 -0.305054)
			(stroke
				(width 0.1)
				(type default)
			)
			(layer "F.Fab")
		)
		(fp_line
			(start 0.67945 -0.3048)
			(end 0.67945 0.3048)
			(stroke
				(width 0.1)
				(type default)
			)
			(layer "F.Fab")
		)
		(fp_line
			(start 0.12065 -0.3048)
			(end 0.67945 -0.3048)
			(stroke
				(width 0.1)
				(type default)
			)
			(layer "F.Fab")
		)
		(fp_line
			(start 0.12065 -0.2794)
			(end 0.12065 -0.3048)
			(stroke
				(width 0.1)
				(type default)
			)
			(layer "F.Fab")
		)
		(fp_line
			(start -0.12065 -0.2794)
			(end 0.12065 -0.2794)
			(stroke
				(width 0.1)
				(type default)
			)
			(layer "F.Fab")
		)
		(fp_line
			(start 0.120396 0.2794)
			(end -0.12065 0.2794)
			(stroke
				(width 0.1)
				(type default)
			)
			(layer "F.Fab")
		)
		(fp_line
			(start -0.12065 0.2794)
			(end -0.12065 0.3048)
			(stroke
				(width 0.1)
				(type default)
			)
			(layer "F.Fab")
		)
		(fp_line
			(start 0.67945 0.3048)
			(end 0.120396 0.3048)
			(stroke
				(width 0.1)
				(type default)
			)
			(layer "F.Fab")
		)
		(fp_line
			(start 0.120396 0.3048)
			(end 0.120396 0.2794)
			(stroke
				(width 0.1)
				(type default)
			)
			(layer "F.Fab")
		)
		(fp_line
			(start -0.12065 0.3048)
			(end -0.67945 0.3048)
			(stroke
				(width 0.1)
				(type default)
			)
			(layer "F.Fab")
		)
		(fp_line
			(start -0.67945 0.3048)
			(end -0.67945 -0.305054)
			(stroke
				(width 0.1)
				(type default)
			)
			(layer "F.Fab")
		)
		(pad "1" smd circle
			(at -0.40005 0 90)
			(size 0 0)
			(layers "F.Cu" "F.Mask" "F.Paste")
			(net "P3V3_AUX")
		)
		(pad "2" smd circle
			(at 0.40005 0 90)
			(size 0 0)
			(layers "F.Cu" "F.Mask" "F.Paste")
			(net "RST_USB_HUB_2_R_N")
		)
	)
	(footprint ""
		(layer "F.Cu")
		(at 348.961964 -66.988944)
		(property "Reference" "C146"
			(at 0 0 0)
			(layer "F.SilkS")
			(hide yes)
			(effects
				(font
					(size 1.27 1.27)
				)
			)
		)
		(property "Value" ""
			(at 0 0 0)
			(layer "F.Fab")
			(effects
				(font
					(size 1.27 1.27)
				)
			)
		)
		(duplicate_pad_numbers_are_jumpers no)
		(fp_line
			(start -0.299974 -0.150114)
			(end 0.299974 -0.150114)
			(stroke
				(width 0.1)
				(type default)
			)
			(layer "F.Fab")
		)
		(fp_line
			(start -0.299974 0.150114)
			(end -0.299974 -0.150114)
			(stroke
				(width 0.1)
				(type default)
			)
			(layer "F.Fab")
		)
		(fp_line
			(start 0.299974 -0.150114)
			(end 0.299974 0.150114)
			(stroke
				(width 0.1)
				(type default)
			)
			(layer "F.Fab")
		)
		(fp_line
			(start 0.299974 0.150114)
			(end -0.299974 0.150114)
			(stroke
				(width 0.1)
				(type default)
			)
			(layer "F.Fab")
		)
		(pad "1" smd rect
			(at -0.2667 0)
			(size 0.3048 0.381)
			(layers "F.Cu" "F.Mask" "F.Paste")
			(net "DMI_CPU0_PCH_TX_C_DP<4>")
		)
		(pad "2" smd rect
			(at 0.2667 0)
			(size 0.3048 0.381)
			(layers "F.Cu" "F.Mask" "F.Paste")
			(net "DMI_CPU0_PCH_TX_DP<4>")
		)
		(zone
			(layer "In1.Cu")
			(hatch none 0.5)
			(connect_pads
				(clearance 0)
			)
			(min_thickness 0.25)
			(keepout
				(tracks not_allowed)
				(vias allowed)
				(pads allowed)
				(copperpour not_allowed)
				(footprints allowed)
			)
			(placement
				(enabled no)
				(sheetname "")
			)
			(fill
				(thermal_gap 0.5)
				(thermal_bridge_width 0.5)
				(island_removal_mode 0)
			)
			(polygon
				(pts
					(arc
						(start 348.568264 -66.747644)
						(mid 348.514382 -66.769962)
						(end 348.492064 -66.823844)
					)
					(arc
						(start 348.492064 -67.154044)
						(mid 348.514382 -67.207926)
						(end 348.568264 -67.230244)
					)
					(arc
						(start 348.822264 -67.230244)
						(mid 348.876146 -67.207926)
						(end 348.898464 -67.154044)
					)
					(arc
						(start 348.898464 -66.823844)
						(mid 348.876146 -66.769962)
						(end 348.822264 -66.747644)
					)
				)
			)
		)
		(zone
			(layer "In1.Cu")
			(hatch none 0.5)
			(connect_pads
				(clearance 0)
			)
			(min_thickness 0.25)
			(keepout
				(tracks not_allowed)
				(vias allowed)
				(pads allowed)
				(copperpour not_allowed)
				(footprints allowed)
			)
			(placement
				(enabled no)
				(sheetname "")
			)
			(fill
				(thermal_gap 0.5)
				(thermal_bridge_width 0.5)
				(island_removal_mode 0)
			)
			(polygon
				(pts
					(arc
						(start 349.101664 -66.747644)
						(mid 349.047782 -66.769962)
						(end 349.025464 -66.823844)
					)
					(arc
						(start 349.025464 -67.154044)
						(mid 349.047782 -67.207926)
						(end 349.101664 -67.230244)
					)
					(arc
						(start 349.355664 -67.230244)
						(mid 349.409546 -67.207926)
						(end 349.431864 -67.154044)
					)
					(arc
						(start 349.431864 -66.823844)
						(mid 349.409546 -66.769962)
						(end 349.355664 -66.747644)
					)
				)
			)
		)
	)
)
